(kicad_pcb
	(version 20260206)
	(generator "pcbnew")
	(generator_version "10.0")
	(general
		(thickness 1.6)
		(legacy_teardrops no)
	)
	(paper "A4")
	(title_block
		(title "01162023_DA0F0TEBIF0_F0T_Expander_BD_F_brd_V02_OCP.brd")
		(comment 1 "Grand Teton / footprints 1214-1222 of 9728")
	)
	(layers
		(0 "F.Cu" signal "TOP")
		(4 "In1.Cu" signal "GND")
		(6 "In2.Cu" signal "VCC")
		(8 "In3.Cu" signal "VCC1")
		(10 "In4.Cu" signal "GND1")
		(12 "In5.Cu" signal "IN1")
		(14 "In6.Cu" signal "GND2")
		(16 "In7.Cu" signal "IN2")
		(18 "In8.Cu" signal "GND3")
		(20 "In9.Cu" signal "IN3")
		(22 "In10.Cu" signal "GND4")
		(24 "In11.Cu" signal "IN4")
		(26 "In12.Cu" signal "GND5")
		(28 "In13.Cu" signal "IN5")
		(30 "In14.Cu" signal "GND6")
		(32 "In15.Cu" signal "IN6")
		(34 "In16.Cu" signal "GND7")
		(2 "B.Cu" signal "BOTTOM")
		(9 "F.Adhes" user "F.Adhesive")
		(11 "B.Adhes" user "B.Adhesive")
		(13 "F.Paste" user "Package Geometry/Pastemask Top")
		(15 "B.Paste" user "Package Geometry/Pastemask Bottom")
		(5 "F.SilkS" user "Ref Des/Silkscreen Top")
		(7 "B.SilkS" user "Ref Des/Silkscreen Bottom")
		(1 "F.Mask" user "Board Geometry/Soldermask Top")
		(3 "B.Mask" user "Board Geometry/Soldermask Bottom")
		(17 "Dwgs.User" user "User.Drawings")
		(19 "Cmts.User" user "User.Comments")
		(21 "Eco1.User" user "User.Eco1")
		(23 "Eco2.User" user "User.Eco2")
		(25 "Edge.Cuts" user "Board Geometry/Outline")
		(27 "Margin" user)
		(31 "F.CrtYd" user "Package Geometry/Place Bound Top")
		(29 "B.CrtYd" user "Package Geometry/Place Bound Bottom")
		(35 "F.Fab" user "Ref Des/Assembly Top")
		(33 "B.Fab" user "Ref Des/Assembly Bottom")
	)
	(footprint ""
		(layer "F.Cu")
		(at 377.843796 -311.725564 45)
		(property "Reference" "R1419"
			(at 0 0 45)
			(layer "F.SilkS")
			(hide yes)
			(effects
				(font
					(size 1.27 1.27)
				)
			)
		)
		(property "Value" ""
			(at 0 0 45)
			(layer "F.Fab")
			(effects
				(font
					(size 1.27 1.27)
				)
			)
		)
		(duplicate_pad_numbers_are_jumpers no)
		(fp_line
			(start -0.787389 -0.406267)
			(end 0.787389 -0.406267)
			(stroke
				(width 0.1524)
				(type default)
			)
			(layer "F.SilkS")
		)
		(fp_line
			(start -0.787389 0.406267)
			(end -0.787389 -0.406267)
			(stroke
				(width 0.1524)
				(type default)
			)
			(layer "F.SilkS")
		)
		(fp_line
			(start 0.787389 -0.406267)
			(end 0.787389 0.406267)
			(stroke
				(width 0.1524)
				(type default)
			)
			(layer "F.SilkS")
		)
		(fp_line
			(start 0.787389 0.406267)
			(end -0.787389 0.406267)
			(stroke
				(width 0.1524)
				(type default)
			)
			(layer "F.SilkS")
		)
		(fp_line
			(start -0.679446 -0.305149)
			(end -0.120695 -0.304969)
			(stroke
				(width 0.1)
				(type default)
			)
			(layer "F.Fab")
		)
		(fp_line
			(start -0.120695 -0.304969)
			(end -0.120695 -0.279466)
			(stroke
				(width 0.1)
				(type default)
			)
			(layer "F.Fab")
		)
		(fp_line
			(start -0.120695 -0.279466)
			(end 0.120695 -0.279466)
			(stroke
				(width 0.1)
				(type default)
			)
			(layer "F.Fab")
		)
		(fp_line
			(start -0.679446 0.30479)
			(end -0.679446 -0.305149)
			(stroke
				(width 0.1)
				(type default)
			)
			(layer "F.Fab")
		)
		(fp_line
			(start 0.120515 -0.30479)
			(end 0.679446 -0.30479)
			(stroke
				(width 0.1)
				(type default)
			)
			(layer "F.Fab")
		)
		(fp_line
			(start 0.120695 -0.279466)
			(end 0.120515 -0.30479)
			(stroke
				(width 0.1)
				(type default)
			)
			(layer "F.Fab")
		)
		(fp_line
			(start -0.120695 0.279466)
			(end -0.120515 0.30479)
			(stroke
				(width 0.1)
				(type default)
			)
			(layer "F.Fab")
		)
		(fp_line
			(start -0.120515 0.30479)
			(end -0.679446 0.30479)
			(stroke
				(width 0.1)
				(type default)
			)
			(layer "F.Fab")
		)
		(fp_line
			(start 0.679446 -0.30479)
			(end 0.679446 0.30479)
			(stroke
				(width 0.1)
				(type default)
			)
			(layer "F.Fab")
		)
		(fp_line
			(start 0.120335 0.279466)
			(end -0.120695 0.279466)
			(stroke
				(width 0.1)
				(type default)
			)
			(layer "F.Fab")
		)
		(fp_line
			(start 0.120515 0.30479)
			(end 0.120335 0.279466)
			(stroke
				(width 0.1)
				(type default)
			)
			(layer "F.Fab")
		)
		(fp_line
			(start 0.679446 0.30479)
			(end 0.120515 0.30479)
			(stroke
				(width 0.1)
				(type default)
			)
			(layer "F.Fab")
		)
		(pad "1" smd circle
			(at -0.40005 0 45)
			(size 0 0)
			(layers "F.Cu" "F.Mask" "F.Paste")
			(net "GND")
		)
		(pad "2" smd circle
			(at 0.40005 0 45)
			(size 0 0)
			(layers "F.Cu" "F.Mask" "F.Paste")
			(net "PEX3_DBG_SEL1")
		)
	)
	(footprint ""
		(layer "F.Cu")
		(at 430.961546 -121.391172 180)
		(property "Reference" "C662"
			(at 0 0 180)
			(layer "F.SilkS")
			(hide yes)
			(effects
				(font
					(size 1.27 1.27)
				)
			)
		)
		(property "Value" ""
			(at 0 0 180)
			(layer "F.Fab")
			(effects
				(font
					(size 1.27 1.27)
				)
			)
		)
		(duplicate_pad_numbers_are_jumpers no)
		(fp_line
			(start 0.299974 0.150114)
			(end -0.299974 0.150114)
			(stroke
				(width 0.1)
				(type default)
			)
			(layer "F.Fab")
		)
		(fp_line
			(start 0.299974 -0.150114)
			(end 0.299974 0.150114)
			(stroke
				(width 0.1)
				(type default)
			)
			(layer "F.Fab")
		)
		(fp_line
			(start -0.299974 0.150114)
			(end -0.299974 -0.150114)
			(stroke
				(width 0.1)
				(type default)
			)
			(layer "F.Fab")
		)
		(fp_line
			(start -0.299974 -0.150114)
			(end 0.299974 -0.150114)
			(stroke
				(width 0.1)
				(type default)
			)
			(layer "F.Fab")
		)
		(pad "1" smd rect
			(at -0.2667 0 180)
			(size 0.3048 0.381)
			(layers "F.Cu" "F.Mask" "F.Paste")
			(net "P5E_PEX3_STN0_TX_DP<1>")
		)
		(pad "2" smd rect
			(at 0.2667 0 180)
			(size 0.3048 0.381)
			(layers "F.Cu" "F.Mask" "F.Paste")
			(net "P5E_PEX3_STN0_TX_C_DP<1>")
		)
	)
	(footprint ""
		(layer "F.Cu")
		(at 39.280592 -121.919746)
		(property "Reference" "C46"
			(at 0 0 0)
			(layer "F.SilkS")
			(hide yes)
			(effects
				(font
					(size 1.27 1.27)
				)
			)
		)
		(property "Value" ""
			(at 0 0 0)
			(layer "F.Fab")
			(effects
				(font
					(size 1.27 1.27)
				)
			)
		)
		(duplicate_pad_numbers_are_jumpers no)
		(fp_line
			(start -0.299974 -0.150114)
			(end 0.299974 -0.150114)
			(stroke
				(width 0.1)
				(type default)
			)
			(layer "F.Fab")
		)
		(fp_line
			(start -0.299974 0.150114)
			(end -0.299974 -0.150114)
			(stroke
				(width 0.1)
				(type default)
			)
			(layer "F.Fab")
		)
		(fp_line
			(start 0.299974 -0.150114)
			(end 0.299974 0.150114)
			(stroke
				(width 0.1)
				(type default)
			)
			(layer "F.Fab")
		)
		(fp_line
			(start 0.299974 0.150114)
			(end -0.299974 0.150114)
			(stroke
				(width 0.1)
				(type default)
			)
			(layer "F.Fab")
		)
		(pad "1" smd rect
			(at -0.2667 0)
			(size 0.3048 0.381)
			(layers "F.Cu" "F.Mask" "F.Paste")
			(net "P5E_PEX0_STN1_TX_DP<25>")
		)
		(pad "2" smd rect
			(at 0.2667 0)
			(size 0.3048 0.381)
			(layers "F.Cu" "F.Mask" "F.Paste")
			(net "P5E_PEX0_STN1_TX_C_DP<25>")
		)
	)
	(footprint ""
		(layer "F.Cu")
		(at 251.608336 -142.455392 180)
		(property "Reference" "R727"
			(at 0 0 180)
			(layer "F.SilkS")
			(hide yes)
			(effects
				(font
					(size 1.27 1.27)
				)
			)
		)
		(property "Value" ""
			(at 0 0 180)
			(layer "F.Fab")
			(effects
				(font
					(size 1.27 1.27)
				)
			)
		)
		(duplicate_pad_numbers_are_jumpers no)
		(fp_line
			(start 3.937508 1.8796)
			(end 3.937508 -1.8796)
			(stroke
				(width 0.1524)
				(type default)
			)
			(layer "F.SilkS")
		)
		(fp_line
			(start 3.937508 -1.8796)
			(end -3.937508 -1.8796)
			(stroke
				(width 0.1524)
				(type default)
			)
			(layer "F.SilkS")
		)
		(fp_line
			(start -3.937508 1.8796)
			(end 3.937508 1.8796)
			(stroke
				(width 0.1524)
				(type default)
			)
			(layer "F.SilkS")
		)
		(fp_line
			(start -3.937508 -1.8796)
			(end -3.937508 1.8796)
			(stroke
				(width 0.1524)
				(type default)
			)
			(layer "F.SilkS")
		)
		(fp_line
			(start 3.275076 1.674876)
			(end 3.275076 -1.674876)
			(stroke
				(width 0.1)
				(type default)
			)
			(layer "F.Fab")
		)
		(fp_line
			(start 3.275076 -1.674876)
			(end -3.275076 -1.674876)
			(stroke
				(width 0.1)
				(type default)
			)
			(layer "F.Fab")
		)
		(fp_line
			(start -3.275076 1.674876)
			(end 3.275076 1.674876)
			(stroke
				(width 0.1)
				(type default)
			)
			(layer "F.Fab")
		)
		(fp_line
			(start -3.275076 -1.674876)
			(end -3.275076 1.674876)
			(stroke
				(width 0.1)
				(type default)
			)
			(layer "F.Fab")
		)
		(pad "1" smd rect
			(at -2.350008 0 180)
			(size 2.921 3.5052)
			(layers "F.Cu" "F.Mask" "F.Paste")
			(net "P12V_NIC4")
		)
		(pad "2" smd rect
			(at 2.350008 0 180)
			(size 2.921 3.5052)
			(layers "F.Cu" "F.Mask" "F.Paste")
			(net "P12V_NIC4_R")
		)
	)
	(footprint ""
		(layer "F.Cu")
		(at 23.330408 -356.244906 90)
		(property "Reference" "C188"
			(at 0 0 90)
			(layer "F.SilkS")
			(hide yes)
			(effects
				(font
					(size 1.27 1.27)
				)
			)
		)
		(property "Value" ""
			(at 0 0 90)
			(layer "F.Fab")
			(effects
				(font
					(size 1.27 1.27)
				)
			)
		)
		(duplicate_pad_numbers_are_jumpers no)
		(fp_line
			(start 0.299974 -0.150114)
			(end 0.299974 0.150114)
			(stroke
				(width 0.1)
				(type default)
			)
			(layer "F.Fab")
		)
		(fp_line
			(start -0.299974 -0.150114)
			(end 0.299974 -0.150114)
			(stroke
				(width 0.1)
				(type default)
			)
			(layer "F.Fab")
		)
		(fp_line
			(start 0.299974 0.150114)
			(end -0.299974 0.150114)
			(stroke
				(width 0.1)
				(type default)
			)
			(layer "F.Fab")
		)
		(fp_line
			(start -0.299974 0.150114)
			(end -0.299974 -0.150114)
			(stroke
				(width 0.1)
				(type default)
			)
			(layer "F.Fab")
		)
		(pad "1" smd rect
			(at -0.2667 0 90)
			(size 0.3048 0.381)
			(layers "F.Cu" "F.Mask" "F.Paste")
			(net "P5E_PEX0_STN7_TX_DN<114>")
		)
		(pad "2" smd rect
			(at 0.2667 0 90)
			(size 0.3048 0.381)
			(layers "F.Cu" "F.Mask" "F.Paste")
			(net "P5E_PEX0_STN7_TX_C_DN<114>")
		)
	)
	(footprint ""
		(layer "F.Cu")
		(at 274.089622 -343.952322 90)
		(property "Reference" "C2345"
			(at 0 0 90)
			(layer "F.SilkS")
			(hide yes)
			(effects
				(font
					(size 1.27 1.27)
				)
			)
		)
		(property "Value" ""
			(at 0 0 90)
			(layer "F.Fab")
			(effects
				(font
					(size 1.27 1.27)
				)
			)
		)
		(duplicate_pad_numbers_are_jumpers no)
		(fp_line
			(start 0.299974 -0.150114)
			(end 0.299974 0.150114)
			(stroke
				(width 0.1)
				(type default)
			)
			(layer "F.Fab")
		)
		(fp_line
			(start -0.299974 -0.150114)
			(end 0.299974 -0.150114)
			(stroke
				(width 0.1)
				(type default)
			)
			(layer "F.Fab")
		)
		(fp_line
			(start 0.299974 0.150114)
			(end -0.299974 0.150114)
			(stroke
				(width 0.1)
				(type default)
			)
			(layer "F.Fab")
		)
		(fp_line
			(start -0.299974 0.150114)
			(end -0.299974 -0.150114)
			(stroke
				(width 0.1)
				(type default)
			)
			(layer "F.Fab")
		)
		(pad "1" smd rect
			(at -0.2667 0 90)
			(size 0.3048 0.381)
			(layers "F.Cu" "F.Mask" "F.Paste")
			(net "P5E_PEX2_STN4_TX_DP<77>")
		)
		(pad "2" smd rect
			(at 0.2667 0 90)
			(size 0.3048 0.381)
			(layers "F.Cu" "F.Mask" "F.Paste")
			(net "P5E_PEX2_STN4_TX_C_DP<77>")
		)
	)
	(footprint ""
		(layer "F.Cu")
		(at 364.809532 -357.96601 90)
		(property "Reference" "C4168"
			(at 0 0 90)
			(layer "F.SilkS")
			(hide yes)
			(effects
				(font
					(size 1.27 1.27)
				)
			)
		)
		(property "Value" ""
			(at 0 0 90)
			(layer "F.Fab")
			(effects
				(font
					(size 1.27 1.27)
				)
			)
		)
		(duplicate_pad_numbers_are_jumpers no)
		(fp_line
			(start 0.7874 -0.4064)
			(end 0.7874 0.4064)
			(stroke
				(width 0.1524)
				(type default)
			)
			(layer "F.SilkS")
		)
		(fp_line
			(start -0.7874 -0.4064)
			(end 0.7874 -0.4064)
			(stroke
				(width 0.1524)
				(type default)
			)
			(layer "F.SilkS")
		)
		(fp_line
			(start 0.7874 0.4064)
			(end -0.7874 0.4064)
			(stroke
				(width 0.1524)
				(type default)
			)
			(layer "F.SilkS")
		)
		(fp_line
			(start -0.7874 0.4064)
			(end -0.7874 -0.4064)
			(stroke
				(width 0.1524)
				(type default)
			)
			(layer "F.SilkS")
		)
		(fp_line
			(start -0.12065 -0.305054)
			(end -0.12065 -0.2794)
			(stroke
				(width 0.1)
				(type default)
			)
			(layer "F.Fab")
		)
		(fp_line
			(start -0.67945 -0.305054)
			(end -0.12065 -0.305054)
			(stroke
				(width 0.1)
				(type default)
			)
			(layer "F.Fab")
		)
		(fp_line
			(start 0.67945 -0.3048)
			(end 0.67945 0.3048)
			(stroke
				(width 0.1)
				(type default)
			)
			(layer "F.Fab")
		)
		(fp_line
			(start 0.12065 -0.3048)
			(end 0.67945 -0.3048)
			(stroke
				(width 0.1)
				(type default)
			)
			(layer "F.Fab")
		)
		(fp_line
			(start 0.12065 -0.2794)
			(end 0.12065 -0.3048)
			(stroke
				(width 0.1)
				(type default)
			)
			(layer "F.Fab")
		)
		(fp_line
			(start -0.12065 -0.2794)
			(end 0.12065 -0.2794)
			(stroke
				(width 0.1)
				(type default)
			)
			(layer "F.Fab")
		)
		(fp_line
			(start 0.120396 0.2794)
			(end -0.12065 0.2794)
			(stroke
				(width 0.1)
				(type default)
			)
			(layer "F.Fab")
		)
		(fp_line
			(start -0.12065 0.2794)
			(end -0.12065 0.3048)
			(stroke
				(width 0.1)
				(type default)
			)
			(layer "F.Fab")
		)
		(fp_line
			(start 0.67945 0.3048)
			(end 0.120396 0.3048)
			(stroke
				(width 0.1)
				(type default)
			)
			(layer "F.Fab")
		)
		(fp_line
			(start 0.120396 0.3048)
			(end 0.120396 0.2794)
			(stroke
				(width 0.1)
				(type default)
			)
			(layer "F.Fab")
		)
		(fp_line
			(start -0.12065 0.3048)
			(end -0.67945 0.3048)
			(stroke
				(width 0.1)
				(type default)
			)
			(layer "F.Fab")
		)
		(fp_line
			(start -0.67945 0.3048)
			(end -0.67945 -0.305054)
			(stroke
				(width 0.1)
				(type default)
			)
			(layer "F.Fab")
		)
		(pad "1" smd circle
			(at -0.40005 0 90)
			(size 0 0)
			(layers "F.Cu" "F.Mask" "F.Paste")
			(net "GND")
		)
		(pad "2" smd circle
			(at 0.40005 0 90)
			(size 0 0)
			(layers "F.Cu" "F.Mask" "F.Paste")
			(net "RST_MB_BIC_N")
		)
	)
	(footprint ""
		(layer "F.Cu")
		(at 154.860244 -116.7384)
		(property "Reference" "R141"
			(at 0 0 0)
			(layer "F.SilkS")
			(hide yes)
			(effects
				(font
					(size 1.27 1.27)
				)
			)
		)
		(property "Value" ""
			(at 0 0 0)
			(layer "F.Fab")
			(effects
				(font
					(size 1.27 1.27)
				)
			)
		)
		(duplicate_pad_numbers_are_jumpers no)
		(fp_line
			(start -0.7874 -0.4064)
			(end 0.7874 -0.4064)
			(stroke
				(width 0.1524)
				(type default)
			)
			(layer "F.SilkS")
		)
		(fp_line
			(start -0.7874 0.4064)
			(end -0.7874 -0.4064)
			(stroke
				(width 0.1524)
				(type default)
			)
			(layer "F.SilkS")
		)
		(fp_line
			(start 0.7874 -0.4064)
			(end 0.7874 0.4064)
			(stroke
				(width 0.1524)
				(type default)
			)
			(layer "F.SilkS")
		)
		(fp_line
			(start 0.7874 0.4064)
			(end -0.7874 0.4064)
			(stroke
				(width 0.1524)
				(type default)
			)
			(layer "F.SilkS")
		)
		(fp_line
			(start -0.67945 -0.305054)
			(end -0.12065 -0.305054)
			(stroke
				(width 0.1)
				(type default)
			)
			(layer "F.Fab")
		)
		(fp_line
			(start -0.67945 0.3048)
			(end -0.67945 -0.305054)
			(stroke
				(width 0.1)
				(type default)
			)
			(layer "F.Fab")
		)
		(fp_line
			(start -0.12065 -0.305054)
			(end -0.12065 -0.2794)
			(stroke
				(width 0.1)
				(type default)
			)
			(layer "F.Fab")
		)
		(fp_line
			(start -0.12065 -0.2794)
			(end 0.12065 -0.2794)
			(stroke
				(width 0.1)
				(type default)
			)
			(layer "F.Fab")
		)
		(fp_line
			(start -0.12065 0.2794)
			(end -0.12065 0.3048)
			(stroke
				(width 0.1)
				(type default)
			)
			(layer "F.Fab")
		)
		(fp_line
			(start -0.12065 0.3048)
			(end -0.67945 0.3048)
			(stroke
				(width 0.1)
				(type default)
			)
			(layer "F.Fab")
		)
		(fp_line
			(start 0.120396 0.2794)
			(end -0.12065 0.2794)
			(stroke
				(width 0.1)
				(type default)
			)
			(layer "F.Fab")
		)
		(fp_line
			(start 0.120396 0.3048)
			(end 0.120396 0.2794)
			(stroke
				(width 0.1)
				(type default)
			)
			(layer "F.Fab")
		)
		(fp_line
			(start 0.12065 -0.3048)
			(end 0.67945 -0.3048)
			(stroke
				(width 0.1)
				(type default)
			)
			(layer "F.Fab")
		)
		(fp_line
			(start 0.12065 -0.2794)
			(end 0.12065 -0.3048)
			(stroke
				(width 0.1)
				(type default)
			)
			(layer "F.Fab")
		)
		(fp_line
			(start 0.67945 -0.3048)
			(end 0.67945 0.3048)
			(stroke
				(width 0.1)
				(type default)
			)
			(layer "F.Fab")
		)
		(fp_line
			(start 0.67945 0.3048)
			(end 0.120396 0.3048)
			(stroke
				(width 0.1)
				(type default)
			)
			(layer "F.Fab")
		)
		(pad "1" smd circle
			(at -0.40005 0)
			(size 0 0)
			(layers "F.Cu" "F.Mask" "F.Paste")
			(net "PRSNT_NIC2_N")
		)
		(pad "2" smd circle
			(at 0.40005 0)
			(size 0 0)
			(layers "F.Cu" "F.Mask" "F.Paste")
			(net "PRSNTB0_NIC2_N")
		)
	)
	(footprint ""
		(layer "F.Cu")
		(at 219.825316 -121.742962 180)
		(property "Reference" "R5959"
			(at 0 0 180)
			(layer "F.SilkS")
			(hide yes)
			(effects
				(font
					(size 1.27 1.27)
				)
			)
		)
		(property "Value" ""
			(at 0 0 180)
			(layer "F.Fab")
			(effects
				(font
					(size 1.27 1.27)
				)
			)
		)
		(duplicate_pad_numbers_are_jumpers no)
		(fp_line
			(start 0.7874 0.4064)
			(end -0.7874 0.4064)
			(stroke
				(width 0.1524)
				(type default)
			)
			(layer "F.SilkS")
		)
		(fp_line
			(start 0.7874 -0.4064)
			(end 0.7874 0.4064)
			(stroke
				(width 0.1524)
				(type default)
			)
			(layer "F.SilkS")
		)
		(fp_line
			(start -0.7874 0.4064)
			(end -0.7874 -0.4064)
			(stroke
				(width 0.1524)
				(type default)
			)
			(layer "F.SilkS")
		)
		(fp_line
			(start -0.7874 -0.4064)
			(end 0.7874 -0.4064)
			(stroke
				(width 0.1524)
				(type default)
			)
			(layer "F.SilkS")
		)
		(fp_line
			(start 0.67945 0.3048)
			(end 0.120396 0.3048)
			(stroke
				(width 0.1)
				(type default)
			)
			(layer "F.Fab")
		)
		(fp_line
			(start 0.67945 -0.3048)
			(end 0.67945 0.3048)
			(stroke
				(width 0.1)
				(type default)
			)
			(layer "F.Fab")
		)
		(fp_line
			(start 0.12065 -0.2794)
			(end 0.12065 -0.3048)
			(stroke
				(width 0.1)
				(type default)
			)
			(layer "F.Fab")
		)
		(fp_line
			(start 0.12065 -0.3048)
			(end 0.67945 -0.3048)
			(stroke
				(width 0.1)
				(type default)
			)
			(layer "F.Fab")
		)
		(fp_line
			(start 0.120396 0.3048)
			(end 0.120396 0.2794)
			(stroke
				(width 0.1)
				(type default)
			)
			(layer "F.Fab")
		)
		(fp_line
			(start 0.120396 0.2794)
			(end -0.12065 0.2794)
			(stroke
				(width 0.1)
				(type default)
			)
			(layer "F.Fab")
		)
		(fp_line
			(start -0.12065 0.3048)
			(end -0.67945 0.3048)
			(stroke
				(width 0.1)
				(type default)
			)
			(layer "F.Fab")
		)
		(fp_line
			(start -0.12065 0.2794)
			(end -0.12065 0.3048)
			(stroke
				(width 0.1)
				(type default)
			)
			(layer "F.Fab")
		)
		(fp_line
			(start -0.12065 -0.2794)
			(end 0.12065 -0.2794)
			(stroke
				(width 0.1)
				(type default)
			)
			(layer "F.Fab")
		)
		(fp_line
			(start -0.12065 -0.305054)
			(end -0.12065 -0.2794)
			(stroke
				(width 0.1)
				(type default)
			)
			(layer "F.Fab")
		)
		(fp_line
			(start -0.67945 0.3048)
			(end -0.67945 -0.305054)
			(stroke
				(width 0.1)
				(type default)
			)
			(layer "F.Fab")
		)
		(fp_line
			(start -0.67945 -0.305054)
			(end -0.12065 -0.305054)
			(stroke
				(width 0.1)
				(type default)
			)
			(layer "F.Fab")
		)
		(pad "1" smd circle
			(at -0.40005 0 180)
			(size 0 0)
			(layers "F.Cu" "F.Mask" "F.Paste")
			(net "PWRGD_P3V3_NIC3_D")
		)
		(pad "2" smd circle
			(at 0.40005 0 180)
			(size 0 0)
			(layers "F.Cu" "F.Mask" "F.Paste")
			(net "PWRGD_P3V3_NIC3_R")
		)
	)
)
